(kicad_pcb
	(version 20260206)
	(generator "pcbnew")
	(generator_version "10.0")
	(general
		(thickness 1.6)
		(legacy_teardrops no)
	)
	(paper "A4")
	(title_block
		(title "12092022_DA0F0TMDCD0_F0T_Management_Board_D_brd_V3_OCP.brd")
		(comment 1 "Grand Teton / footprints 678-683 of 1440")
	)
	(layers
		(0 "F.Cu" signal "TOP")
		(4 "In1.Cu" signal "GND")
		(6 "In2.Cu" signal "IN1")
		(8 "In3.Cu" signal "GND1")
		(10 "In4.Cu" signal "IN2")
		(12 "In5.Cu" signal "VCC")
		(14 "In6.Cu" signal "VCC1")
		(16 "In7.Cu" signal "IN3")
		(18 "In8.Cu" signal "GND2")
		(20 "In9.Cu" signal "IN4")
		(22 "In10.Cu" signal "GND3")
		(2 "B.Cu" signal "BOTTOM")
		(9 "F.Adhes" user "F.Adhesive")
		(11 "B.Adhes" user "B.Adhesive")
		(13 "F.Paste" user "Package Geometry/Pastemask Top")
		(15 "B.Paste" user "Package Geometry/Pastemask Bottom")
		(5 "F.SilkS" user "Ref Des/Silkscreen Top")
		(7 "B.SilkS" user "Ref Des/Silkscreen Bottom")
		(1 "F.Mask" user "Board Geometry/Soldermask Top")
		(3 "B.Mask" user "Board Geometry/Soldermask Bottom")
		(17 "Dwgs.User" user "User.Drawings")
		(19 "Cmts.User" user "User.Comments")
		(21 "Eco1.User" user "User.Eco1")
		(23 "Eco2.User" user "User.Eco2")
		(25 "Edge.Cuts" user "Board Geometry/Outline")
		(27 "Margin" user)
		(31 "F.CrtYd" user "Package Geometry/Place Bound Top")
		(29 "B.CrtYd" user "Package Geometry/Place Bound Bottom")
		(35 "F.Fab" user "Ref Des/Assembly Top")
		(33 "B.Fab" user "Ref Des/Assembly Bottom")
	)
	(footprint ""
		(layer "F.Cu")
		(at 77.47 -21.336 180)
		(property "Reference" "D19"
			(at 1.143 1.11633 0)
			(unlocked yes)
			(layer "F.SilkS")
			(effects
				(font
					(size 0.7874 0.5842)
					(thickness 0.1524)
				)
				(justify left)
			)
		)
		(property "Value" ""
			(at 0 0 180)
			(layer "F.Fab")
			(effects
				(font
					(size 1.27 1.27)
				)
			)
		)
		(duplicate_pad_numbers_are_jumpers no)
		(fp_line
			(start 1.16078 0.4826)
			(end -0.64008 0.4826)
			(stroke
				(width 0.1524)
				(type default)
			)
			(layer "F.SilkS")
		)
		(fp_line
			(start 1.16078 -0.4826)
			(end 1.16078 0.4826)
			(stroke
				(width 0.1524)
				(type default)
			)
			(layer "F.SilkS")
		)
		(fp_line
			(start 1.03378 0.4826)
			(end -0.79248 0.4826)
			(stroke
				(width 0.1524)
				(type default)
			)
			(layer "F.SilkS")
		)
		(fp_line
			(start 1.03378 -0.4826)
			(end 1.03378 0.4826)
			(stroke
				(width 0.1524)
				(type default)
			)
			(layer "F.SilkS")
		)
		(fp_line
			(start 0.90678 0.4826)
			(end -0.90678 0.4826)
			(stroke
				(width 0.1524)
				(type default)
			)
			(layer "F.SilkS")
		)
		(fp_line
			(start 0.90678 -0.4826)
			(end 0.90678 0.4826)
			(stroke
				(width 0.1524)
				(type default)
			)
			(layer "F.SilkS")
		)
		(fp_line
			(start -0.64008 -0.4826)
			(end 1.16078 -0.4826)
			(stroke
				(width 0.1524)
				(type default)
			)
			(layer "F.SilkS")
		)
		(fp_line
			(start -0.79248 -0.4826)
			(end 1.03378 -0.4826)
			(stroke
				(width 0.1524)
				(type default)
			)
			(layer "F.SilkS")
		)
		(fp_line
			(start -0.89408 -0.4826)
			(end 0.90678 -0.4826)
			(stroke
				(width 0.1524)
				(type default)
			)
			(layer "F.SilkS")
		)
		(fp_line
			(start -0.90678 0.4826)
			(end -0.90678 -0.4699)
			(stroke
				(width 0.1524)
				(type default)
			)
			(layer "F.SilkS")
		)
		(fp_line
			(start 0.499872 0.249936)
			(end -0.499872 0.249936)
			(stroke
				(width 0.1)
				(type default)
			)
			(layer "F.Fab")
		)
		(fp_line
			(start 0.499872 -0.249936)
			(end 0.499872 0.249936)
			(stroke
				(width 0.1)
				(type default)
			)
			(layer "F.Fab")
		)
		(fp_line
			(start -0.499872 0.249936)
			(end -0.499872 -0.249936)
			(stroke
				(width 0.1)
				(type default)
			)
			(layer "F.Fab")
		)
		(fp_line
			(start -0.499872 -0.249936)
			(end 0.499872 -0.249936)
			(stroke
				(width 0.1)
				(type default)
			)
			(layer "F.Fab")
		)
		(pad "A" smd rect
			(at -0.47498 0 180)
			(size 0.6096 0.7112)
			(layers "F.Cu" "F.Mask" "F.Paste")
			(net "P3V3_AUX")
		)
		(pad "C" smd rect
			(at 0.47498 0 180)
			(size 0.6096 0.7112)
			(layers "F.Cu" "F.Mask" "F.Paste")
			(net "FM_UARTSW_MSB_R1_N")
		)
	)
	(footprint ""
		(layer "F.Cu")
		(at 52.991258 -34.637726 -90)
		(property "Reference" "R639"
			(at 0 0 270)
			(layer "F.SilkS")
			(hide yes)
			(effects
				(font
					(size 1.27 1.27)
				)
			)
		)
		(property "Value" ""
			(at 0 0 270)
			(layer "F.Fab")
			(effects
				(font
					(size 1.27 1.27)
				)
			)
		)
		(duplicate_pad_numbers_are_jumpers no)
		(fp_line
			(start -0.7874 0.4064)
			(end -0.7874 -0.4064)
			(stroke
				(width 0.1524)
				(type default)
			)
			(layer "F.SilkS")
		)
		(fp_line
			(start 0.7874 0.4064)
			(end -0.7874 0.4064)
			(stroke
				(width 0.1524)
				(type default)
			)
			(layer "F.SilkS")
		)
		(fp_line
			(start -0.7874 -0.4064)
			(end 0.7874 -0.4064)
			(stroke
				(width 0.1524)
				(type default)
			)
			(layer "F.SilkS")
		)
		(fp_line
			(start 0.7874 -0.4064)
			(end 0.7874 0.4064)
			(stroke
				(width 0.1524)
				(type default)
			)
			(layer "F.SilkS")
		)
		(fp_line
			(start -0.67945 0.3048)
			(end -0.67945 -0.305054)
			(stroke
				(width 0.1)
				(type default)
			)
			(layer "F.Fab")
		)
		(fp_line
			(start -0.12065 0.3048)
			(end -0.67945 0.3048)
			(stroke
				(width 0.1)
				(type default)
			)
			(layer "F.Fab")
		)
		(fp_line
			(start 0.120396 0.3048)
			(end 0.120396 0.2794)
			(stroke
				(width 0.1)
				(type default)
			)
			(layer "F.Fab")
		)
		(fp_line
			(start 0.67945 0.3048)
			(end 0.120396 0.3048)
			(stroke
				(width 0.1)
				(type default)
			)
			(layer "F.Fab")
		)
		(fp_line
			(start -0.12065 0.2794)
			(end -0.12065 0.3048)
			(stroke
				(width 0.1)
				(type default)
			)
			(layer "F.Fab")
		)
		(fp_line
			(start 0.120396 0.2794)
			(end -0.12065 0.2794)
			(stroke
				(width 0.1)
				(type default)
			)
			(layer "F.Fab")
		)
		(fp_line
			(start -0.12065 -0.2794)
			(end 0.12065 -0.2794)
			(stroke
				(width 0.1)
				(type default)
			)
			(layer "F.Fab")
		)
		(fp_line
			(start 0.12065 -0.2794)
			(end 0.12065 -0.3048)
			(stroke
				(width 0.1)
				(type default)
			)
			(layer "F.Fab")
		)
		(fp_line
			(start 0.12065 -0.3048)
			(end 0.67945 -0.3048)
			(stroke
				(width 0.1)
				(type default)
			)
			(layer "F.Fab")
		)
		(fp_line
			(start 0.67945 -0.3048)
			(end 0.67945 0.3048)
			(stroke
				(width 0.1)
				(type default)
			)
			(layer "F.Fab")
		)
		(fp_line
			(start -0.67945 -0.305054)
			(end -0.12065 -0.305054)
			(stroke
				(width 0.1)
				(type default)
			)
			(layer "F.Fab")
		)
		(fp_line
			(start -0.12065 -0.305054)
			(end -0.12065 -0.2794)
			(stroke
				(width 0.1)
				(type default)
			)
			(layer "F.Fab")
		)
		(pad "1" smd circle
			(at -0.40005 0 270)
			(size 0 0)
			(layers "F.Cu" "F.Mask" "F.Paste")
			(net "JTAG_1_BMC_TDI_R")
		)
		(pad "2" smd circle
			(at 0.40005 0 270)
			(size 0 0)
			(layers "F.Cu" "F.Mask" "F.Paste")
			(net "JTAG_MB_TDI")
		)
	)
	(footprint ""
		(layer "F.Cu")
		(at 61.70676 -66.031364 -90)
		(property "Reference" "R799"
			(at 0 0 270)
			(layer "F.SilkS")
			(hide yes)
			(effects
				(font
					(size 1.27 1.27)
				)
			)
		)
		(property "Value" ""
			(at 0 0 270)
			(layer "F.Fab")
			(effects
				(font
					(size 1.27 1.27)
				)
			)
		)
		(duplicate_pad_numbers_are_jumpers no)
		(fp_line
			(start -0.7874 0.4064)
			(end -0.7874 -0.4064)
			(stroke
				(width 0.1524)
				(type default)
			)
			(layer "F.SilkS")
		)
		(fp_line
			(start 0.7874 0.4064)
			(end -0.7874 0.4064)
			(stroke
				(width 0.1524)
				(type default)
			)
			(layer "F.SilkS")
		)
		(fp_line
			(start -0.7874 -0.4064)
			(end 0.7874 -0.4064)
			(stroke
				(width 0.1524)
				(type default)
			)
			(layer "F.SilkS")
		)
		(fp_line
			(start 0.7874 -0.4064)
			(end 0.7874 0.4064)
			(stroke
				(width 0.1524)
				(type default)
			)
			(layer "F.SilkS")
		)
		(fp_line
			(start -0.67945 0.3048)
			(end -0.67945 -0.305054)
			(stroke
				(width 0.1)
				(type default)
			)
			(layer "F.Fab")
		)
		(fp_line
			(start -0.12065 0.3048)
			(end -0.67945 0.3048)
			(stroke
				(width 0.1)
				(type default)
			)
			(layer "F.Fab")
		)
		(fp_line
			(start 0.120396 0.3048)
			(end 0.120396 0.2794)
			(stroke
				(width 0.1)
				(type default)
			)
			(layer "F.Fab")
		)
		(fp_line
			(start 0.67945 0.3048)
			(end 0.120396 0.3048)
			(stroke
				(width 0.1)
				(type default)
			)
			(layer "F.Fab")
		)
		(fp_line
			(start -0.12065 0.2794)
			(end -0.12065 0.3048)
			(stroke
				(width 0.1)
				(type default)
			)
			(layer "F.Fab")
		)
		(fp_line
			(start 0.120396 0.2794)
			(end -0.12065 0.2794)
			(stroke
				(width 0.1)
				(type default)
			)
			(layer "F.Fab")
		)
		(fp_line
			(start -0.12065 -0.2794)
			(end 0.12065 -0.2794)
			(stroke
				(width 0.1)
				(type default)
			)
			(layer "F.Fab")
		)
		(fp_line
			(start 0.12065 -0.2794)
			(end 0.12065 -0.3048)
			(stroke
				(width 0.1)
				(type default)
			)
			(layer "F.Fab")
		)
		(fp_line
			(start 0.12065 -0.3048)
			(end 0.67945 -0.3048)
			(stroke
				(width 0.1)
				(type default)
			)
			(layer "F.Fab")
		)
		(fp_line
			(start 0.67945 -0.3048)
			(end 0.67945 0.3048)
			(stroke
				(width 0.1)
				(type default)
			)
			(layer "F.Fab")
		)
		(fp_line
			(start -0.67945 -0.305054)
			(end -0.12065 -0.305054)
			(stroke
				(width 0.1)
				(type default)
			)
			(layer "F.Fab")
		)
		(fp_line
			(start -0.12065 -0.305054)
			(end -0.12065 -0.2794)
			(stroke
				(width 0.1)
				(type default)
			)
			(layer "F.Fab")
		)
		(pad "1" smd circle
			(at -0.40005 0 270)
			(size 0 0)
			(layers "F.Cu" "F.Mask" "F.Paste")
			(net "SPI_BMC_BIOS_CS0_N")
		)
		(pad "2" smd circle
			(at 0.40005 0 270)
			(size 0 0)
			(layers "F.Cu" "F.Mask" "F.Paste")
			(net "SPI_BMC_BIOS_CS0_R1_N")
		)
	)
	(footprint ""
		(layer "F.Cu")
		(at 13.169646 -52.008532 -90)
		(property "Reference" "PR521"
			(at 0 0 270)
			(layer "F.SilkS")
			(hide yes)
			(effects
				(font
					(size 1.27 1.27)
				)
			)
		)
		(property "Value" ""
			(at 0 0 270)
			(layer "F.Fab")
			(effects
				(font
					(size 1.27 1.27)
				)
			)
		)
		(duplicate_pad_numbers_are_jumpers no)
		(fp_line
			(start -0.7874 0.4064)
			(end -0.7874 -0.4064)
			(stroke
				(width 0.1524)
				(type default)
			)
			(layer "F.SilkS")
		)
		(fp_line
			(start 0.7874 0.4064)
			(end -0.7874 0.4064)
			(stroke
				(width 0.1524)
				(type default)
			)
			(layer "F.SilkS")
		)
		(fp_line
			(start -0.7874 -0.4064)
			(end 0.7874 -0.4064)
			(stroke
				(width 0.1524)
				(type default)
			)
			(layer "F.SilkS")
		)
		(fp_line
			(start 0.7874 -0.4064)
			(end 0.7874 0.4064)
			(stroke
				(width 0.1524)
				(type default)
			)
			(layer "F.SilkS")
		)
		(fp_line
			(start -0.67945 0.3048)
			(end -0.67945 -0.305054)
			(stroke
				(width 0.1)
				(type default)
			)
			(layer "F.Fab")
		)
		(fp_line
			(start -0.12065 0.3048)
			(end -0.67945 0.3048)
			(stroke
				(width 0.1)
				(type default)
			)
			(layer "F.Fab")
		)
		(fp_line
			(start 0.120396 0.3048)
			(end 0.120396 0.2794)
			(stroke
				(width 0.1)
				(type default)
			)
			(layer "F.Fab")
		)
		(fp_line
			(start 0.67945 0.3048)
			(end 0.120396 0.3048)
			(stroke
				(width 0.1)
				(type default)
			)
			(layer "F.Fab")
		)
		(fp_line
			(start -0.12065 0.2794)
			(end -0.12065 0.3048)
			(stroke
				(width 0.1)
				(type default)
			)
			(layer "F.Fab")
		)
		(fp_line
			(start 0.120396 0.2794)
			(end -0.12065 0.2794)
			(stroke
				(width 0.1)
				(type default)
			)
			(layer "F.Fab")
		)
		(fp_line
			(start -0.12065 -0.2794)
			(end 0.12065 -0.2794)
			(stroke
				(width 0.1)
				(type default)
			)
			(layer "F.Fab")
		)
		(fp_line
			(start 0.12065 -0.2794)
			(end 0.12065 -0.3048)
			(stroke
				(width 0.1)
				(type default)
			)
			(layer "F.Fab")
		)
		(fp_line
			(start 0.12065 -0.3048)
			(end 0.67945 -0.3048)
			(stroke
				(width 0.1)
				(type default)
			)
			(layer "F.Fab")
		)
		(fp_line
			(start 0.67945 -0.3048)
			(end 0.67945 0.3048)
			(stroke
				(width 0.1)
				(type default)
			)
			(layer "F.Fab")
		)
		(fp_line
			(start -0.67945 -0.305054)
			(end -0.12065 -0.305054)
			(stroke
				(width 0.1)
				(type default)
			)
			(layer "F.Fab")
		)
		(fp_line
			(start -0.12065 -0.305054)
			(end -0.12065 -0.2794)
			(stroke
				(width 0.1)
				(type default)
			)
			(layer "F.Fab")
		)
		(pad "1" smd circle
			(at -0.40005 0 270)
			(size 0 0)
			(layers "F.Cu" "F.Mask" "F.Paste")
			(net "P12V_AUX")
		)
		(pad "2" smd circle
			(at 0.40005 0 270)
			(size 0 0)
			(layers "F.Cu" "F.Mask" "F.Paste")
			(net "EN_P5V_AUX")
		)
	)
	(footprint ""
		(layer "F.Cu")
		(at 40.648128 -55.427626 -90)
		(property "Reference" "R832"
			(at 0 0 270)
			(layer "F.SilkS")
			(hide yes)
			(effects
				(font
					(size 1.27 1.27)
				)
			)
		)
		(property "Value" ""
			(at 0 0 270)
			(layer "F.Fab")
			(effects
				(font
					(size 1.27 1.27)
				)
			)
		)
		(duplicate_pad_numbers_are_jumpers no)
		(fp_line
			(start -0.7874 0.4064)
			(end -0.7874 -0.4064)
			(stroke
				(width 0.1524)
				(type default)
			)
			(layer "F.SilkS")
		)
		(fp_line
			(start 0.7874 0.4064)
			(end -0.7874 0.4064)
			(stroke
				(width 0.1524)
				(type default)
			)
			(layer "F.SilkS")
		)
		(fp_line
			(start -0.7874 -0.4064)
			(end 0.7874 -0.4064)
			(stroke
				(width 0.1524)
				(type default)
			)
			(layer "F.SilkS")
		)
		(fp_line
			(start 0.7874 -0.4064)
			(end 0.7874 0.4064)
			(stroke
				(width 0.1524)
				(type default)
			)
			(layer "F.SilkS")
		)
		(fp_line
			(start -0.67945 0.3048)
			(end -0.67945 -0.305054)
			(stroke
				(width 0.1)
				(type default)
			)
			(layer "F.Fab")
		)
		(fp_line
			(start -0.12065 0.3048)
			(end -0.67945 0.3048)
			(stroke
				(width 0.1)
				(type default)
			)
			(layer "F.Fab")
		)
		(fp_line
			(start 0.120396 0.3048)
			(end 0.120396 0.2794)
			(stroke
				(width 0.1)
				(type default)
			)
			(layer "F.Fab")
		)
		(fp_line
			(start 0.67945 0.3048)
			(end 0.120396 0.3048)
			(stroke
				(width 0.1)
				(type default)
			)
			(layer "F.Fab")
		)
		(fp_line
			(start -0.12065 0.2794)
			(end -0.12065 0.3048)
			(stroke
				(width 0.1)
				(type default)
			)
			(layer "F.Fab")
		)
		(fp_line
			(start 0.120396 0.2794)
			(end -0.12065 0.2794)
			(stroke
				(width 0.1)
				(type default)
			)
			(layer "F.Fab")
		)
		(fp_line
			(start -0.12065 -0.2794)
			(end 0.12065 -0.2794)
			(stroke
				(width 0.1)
				(type default)
			)
			(layer "F.Fab")
		)
		(fp_line
			(start 0.12065 -0.2794)
			(end 0.12065 -0.3048)
			(stroke
				(width 0.1)
				(type default)
			)
			(layer "F.Fab")
		)
		(fp_line
			(start 0.12065 -0.3048)
			(end 0.67945 -0.3048)
			(stroke
				(width 0.1)
				(type default)
			)
			(layer "F.Fab")
		)
		(fp_line
			(start 0.67945 -0.3048)
			(end 0.67945 0.3048)
			(stroke
				(width 0.1)
				(type default)
			)
			(layer "F.Fab")
		)
		(fp_line
			(start -0.67945 -0.305054)
			(end -0.12065 -0.305054)
			(stroke
				(width 0.1)
				(type default)
			)
			(layer "F.Fab")
		)
		(fp_line
			(start -0.12065 -0.305054)
			(end -0.12065 -0.2794)
			(stroke
				(width 0.1)
				(type default)
			)
			(layer "F.Fab")
		)
		(pad "1" smd circle
			(at -0.40005 0 270)
			(size 0 0)
			(layers "F.Cu" "F.Mask" "F.Paste")
			(net "U41_ADJ")
		)
		(pad "2" smd circle
			(at 0.40005 0 270)
			(size 0 0)
			(layers "F.Cu" "F.Mask" "F.Paste")
			(net "GND")
		)
	)
	(footprint ""
		(layer "F.Cu")
		(at 27.559 -102.743 -90)
		(property "Reference" "R578"
			(at 0 0 270)
			(layer "F.SilkS")
			(hide yes)
			(effects
				(font
					(size 1.27 1.27)
				)
			)
		)
		(property "Value" ""
			(at 0 0 270)
			(layer "F.Fab")
			(effects
				(font
					(size 1.27 1.27)
				)
			)
		)
		(duplicate_pad_numbers_are_jumpers no)
		(fp_line
			(start -0.7874 0.4064)
			(end -0.7874 -0.4064)
			(stroke
				(width 0.1524)
				(type default)
			)
			(layer "F.SilkS")
		)
		(fp_line
			(start 0.7874 0.4064)
			(end -0.7874 0.4064)
			(stroke
				(width 0.1524)
				(type default)
			)
			(layer "F.SilkS")
		)
		(fp_line
			(start -0.7874 -0.4064)
			(end 0.7874 -0.4064)
			(stroke
				(width 0.1524)
				(type default)
			)
			(layer "F.SilkS")
		)
		(fp_line
			(start 0.7874 -0.4064)
			(end 0.7874 0.4064)
			(stroke
				(width 0.1524)
				(type default)
			)
			(layer "F.SilkS")
		)
		(fp_line
			(start -0.67945 0.3048)
			(end -0.67945 -0.305054)
			(stroke
				(width 0.1)
				(type default)
			)
			(layer "F.Fab")
		)
		(fp_line
			(start -0.12065 0.3048)
			(end -0.67945 0.3048)
			(stroke
				(width 0.1)
				(type default)
			)
			(layer "F.Fab")
		)
		(fp_line
			(start 0.120396 0.3048)
			(end 0.120396 0.2794)
			(stroke
				(width 0.1)
				(type default)
			)
			(layer "F.Fab")
		)
		(fp_line
			(start 0.67945 0.3048)
			(end 0.120396 0.3048)
			(stroke
				(width 0.1)
				(type default)
			)
			(layer "F.Fab")
		)
		(fp_line
			(start -0.12065 0.2794)
			(end -0.12065 0.3048)
			(stroke
				(width 0.1)
				(type default)
			)
			(layer "F.Fab")
		)
		(fp_line
			(start 0.120396 0.2794)
			(end -0.12065 0.2794)
			(stroke
				(width 0.1)
				(type default)
			)
			(layer "F.Fab")
		)
		(fp_line
			(start -0.12065 -0.2794)
			(end 0.12065 -0.2794)
			(stroke
				(width 0.1)
				(type default)
			)
			(layer "F.Fab")
		)
		(fp_line
			(start 0.12065 -0.2794)
			(end 0.12065 -0.3048)
			(stroke
				(width 0.1)
				(type default)
			)
			(layer "F.Fab")
		)
		(fp_line
			(start 0.12065 -0.3048)
			(end 0.67945 -0.3048)
			(stroke
				(width 0.1)
				(type default)
			)
			(layer "F.Fab")
		)
		(fp_line
			(start 0.67945 -0.3048)
			(end 0.67945 0.3048)
			(stroke
				(width 0.1)
				(type default)
			)
			(layer "F.Fab")
		)
		(fp_line
			(start -0.67945 -0.305054)
			(end -0.12065 -0.305054)
			(stroke
				(width 0.1)
				(type default)
			)
			(layer "F.Fab")
		)
		(fp_line
			(start -0.12065 -0.305054)
			(end -0.12065 -0.2794)
			(stroke
				(width 0.1)
				(type default)
			)
			(layer "F.Fab")
		)
		(pad "1" smd circle
			(at -0.40005 0 270)
			(size 0 0)
			(layers "F.Cu" "F.Mask" "F.Paste")
			(net "PWRGD_DSW_PWROK")
		)
		(pad "2" smd circle
			(at 0.40005 0 270)
			(size 0 0)
			(layers "F.Cu" "F.Mask" "F.Paste")
			(net "PWRGD_DSW_PWROK_R2")
		)
	)
)
